# S9S_MB_2U (Grand Teton) — schematic netlist excerpt (pin names and nets, part order shuffled) for the footprints in the layout excerpt that follows; sources: Cadence DE-HDL packaged netlist, KiCad conversion of 03242023_DA0F0TMBIJ0_F0T_Motherboard_J_brd_V01_OCP.brd

PC1282  Q_CAP  1UF 16V 10% X6S  pkg C0402  page 300 : A = SW_P12V_PVCCINFAON_CPU1_FLT ; B = GND
C549  Q_CAP  0.1UF 25V 10% X7R  pkg 0402  page 131 : A = JTAG_RST_DBP_RST_CO_N ; B = GND
J90_CON  TP  NA  pkg TP_BOM ONLY  page 312 : TP = NC

(kicad_pcb
	(version 20260206)
	(generator "pcbnew")
	(generator_version "10.0")
	(general
		(thickness 1.6)
		(legacy_teardrops no)
	)
	(paper "A4")
	(title_block
		(title "03242023_DA0F0TMBIJ0_F0T_Motherboard_J_brd_V01_OCP.brd")
		(comment 1 "Grand Teton / footprints 4084-4086 of 6105")
	)
	(layers
		(0 "F.Cu" signal "TOP")
		(4 "In1.Cu" signal "GND")
		(6 "In2.Cu" signal "IN1")
		(8 "In3.Cu" signal "GND1")
		(10 "In4.Cu" signal "IN2")
		(12 "In5.Cu" signal "GND2")
		(14 "In6.Cu" signal "IN3")
		(16 "In7.Cu" signal "GND3")
		(18 "In8.Cu" signal "VCC")
		(20 "In9.Cu" signal "VCC1")
		(22 "In10.Cu" signal "GND4")
		(24 "In11.Cu" signal "IN4")
		(26 "In12.Cu" signal "GND5")
		(28 "In13.Cu" signal "IN5")
		(30 "In14.Cu" signal "GND6")
		(32 "In15.Cu" signal "IN6")
		(34 "In16.Cu" signal "GND7")
		(2 "B.Cu" signal "BOTTOM")
		(9 "F.Adhes" user "F.Adhesive")
		(11 "B.Adhes" user "B.Adhesive")
		(13 "F.Paste" user "Package Geometry/Pastemask Top")
		(15 "B.Paste" user "Package Geometry/Pastemask Bottom")
		(5 "F.SilkS" user "Ref Des/Silkscreen Top")
		(7 "B.SilkS" user "Ref Des/Silkscreen Bottom")
		(1 "F.Mask" user "Board Geometry/Soldermask Top")
		(3 "B.Mask" user "Board Geometry/Soldermask Bottom")
		(17 "Dwgs.User" user "User.Drawings")
		(19 "Cmts.User" user "User.Comments")
		(21 "Eco1.User" user "User.Eco1")
		(23 "Eco2.User" user "User.Eco2")
		(25 "Edge.Cuts" user "Board Geometry/Outline")
		(27 "Margin" user)
		(31 "F.CrtYd" user "Package Geometry/Place Bound Top")
		(29 "B.CrtYd" user "Package Geometry/Place Bound Bottom")
		(35 "F.Fab" user "Ref Des/Assembly Top")
		(33 "B.Fab" user "Ref Des/Assembly Bottom")
	)
	(footprint ""
		(layer "F.Cu")
		(at 403.941026 -64.040004)
		(property "Reference" "C549"
			(at 0 0 0)
			(layer "F.SilkS")
			(hide yes)
			(effects
				(font
					(size 1.27 1.27)
				)
			)
		)
		(property "Value" ""
			(at 0 0 0)
			(layer "F.Fab")
			(effects
				(font
					(size 1.27 1.27)
				)
			)
		)
		(duplicate_pad_numbers_are_jumpers no)
		(fp_line
			(start -0.7874 -0.4064)
			(end 0.7874 -0.4064)
			(stroke
				(width 0.1524)
				(type default)
			)
			(layer "F.SilkS")
		)
		(fp_line
			(start -0.7874 0.4064)
			(end -0.7874 -0.4064)
			(stroke
				(width 0.1524)
				(type default)
			)
			(layer "F.SilkS")
		)
		(fp_line
			(start 0.7874 -0.4064)
			(end 0.7874 0.4064)
			(stroke
				(width 0.1524)
				(type default)
			)
			(layer "F.SilkS")
		)
		(fp_line
			(start 0.7874 0.4064)
			(end -0.7874 0.4064)
			(stroke
				(width 0.1524)
				(type default)
			)
			(layer "F.SilkS")
		)
		(fp_line
			(start -0.67945 -0.305054)
			(end -0.12065 -0.305054)
			(stroke
				(width 0.1)
				(type default)
			)
			(layer "F.Fab")
		)
		(fp_line
			(start -0.67945 0.3048)
			(end -0.67945 -0.305054)
			(stroke
				(width 0.1)
				(type default)
			)
			(layer "F.Fab")
		)
		(fp_line
			(start -0.12065 -0.305054)
			(end -0.12065 -0.2794)
			(stroke
				(width 0.1)
				(type default)
			)
			(layer "F.Fab")
		)
		(fp_line
			(start -0.12065 -0.2794)
			(end 0.12065 -0.2794)
			(stroke
				(width 0.1)
				(type default)
			)
			(layer "F.Fab")
		)
		(fp_line
			(start -0.12065 0.2794)
			(end -0.12065 0.3048)
			(stroke
				(width 0.1)
				(type default)
			)
			(layer "F.Fab")
		)
		(fp_line
			(start -0.12065 0.3048)
			(end -0.67945 0.3048)
			(stroke
				(width 0.1)
				(type default)
			)
			(layer "F.Fab")
		)
		(fp_line
			(start 0.120396 0.2794)
			(end -0.12065 0.2794)
			(stroke
				(width 0.1)
				(type default)
			)
			(layer "F.Fab")
		)
		(fp_line
			(start 0.120396 0.3048)
			(end 0.120396 0.2794)
			(stroke
				(width 0.1)
				(type default)
			)
			(layer "F.Fab")
		)
		(fp_line
			(start 0.12065 -0.3048)
			(end 0.67945 -0.3048)
			(stroke
				(width 0.1)
				(type default)
			)
			(layer "F.Fab")
		)
		(fp_line
			(start 0.12065 -0.2794)
			(end 0.12065 -0.3048)
			(stroke
				(width 0.1)
				(type default)
			)
			(layer "F.Fab")
		)
		(fp_line
			(start 0.67945 -0.3048)
			(end 0.67945 0.3048)
			(stroke
				(width 0.1)
				(type default)
			)
			(layer "F.Fab")
		)
		(fp_line
			(start 0.67945 0.3048)
			(end 0.120396 0.3048)
			(stroke
				(width 0.1)
				(type default)
			)
			(layer "F.Fab")
		)
		(pad "1" smd circle
			(at -0.40005 0)
			(size 0 0)
			(layers "F.Cu" "F.Mask" "F.Paste")
			(net "JTAG_RST_DBP_RST_CO_N")
		)
		(pad "2" smd circle
			(at 0.40005 0)
			(size 0 0)
			(layers "F.Cu" "F.Mask" "F.Paste")
			(net "GND")
		)
	)
	(footprint ""
		(layer "F.Cu")
		(at 484.125016 -470.302844)
		(property "Reference" "J90_CON"
			(at -3.668776 -2.231644 0)
			(unlocked yes)
			(layer "F.SilkS")
			(effects
				(font
					(size 0.7874 0.5842)
					(thickness 0.1524)
				)
				(justify left)
			)
		)
		(property "Value" ""
			(at 0 0 0)
			(layer "F.Fab")
			(effects
				(font
					(size 1.27 1.27)
				)
			)
		)
		(duplicate_pad_numbers_are_jumpers no)
		(pad "1" smd circle
			(at 0 0)
			(size 0.762 0.762)
			(layers "F.Cu" "F.Mask" "F.Paste")
			(net "Net_8608")
		)
	)
	(footprint ""
		(layer "F.Cu")
		(at 20.906994 -180.682646 90)
		(property "Reference" "PC1282"
			(at 0 0 90)
			(layer "F.SilkS")
			(hide yes)
			(effects
				(font
					(size 1.27 1.27)
				)
			)
		)
		(property "Value" ""
			(at 0 0 90)
			(layer "F.Fab")
			(effects
				(font
					(size 1.27 1.27)
				)
			)
		)
		(duplicate_pad_numbers_are_jumpers no)
		(fp_line
			(start 0.7874 -0.4064)
			(end 0.7874 0.4064)
			(stroke
				(width 0.1524)
				(type default)
			)
			(layer "F.SilkS")
		)
		(fp_line
			(start -0.7874 -0.4064)
			(end 0.7874 -0.4064)
			(stroke
				(width 0.1524)
				(type default)
			)
			(layer "F.SilkS")
		)
		(fp_line
			(start 0.7874 0.4064)
			(end -0.7874 0.4064)
			(stroke
				(width 0.1524)
				(type default)
			)
			(layer "F.SilkS")
		)
		(fp_line
			(start -0.7874 0.4064)
			(end -0.7874 -0.4064)
			(stroke
				(width 0.1524)
				(type default)
			)
			(layer "F.SilkS")
		)
		(fp_line
			(start -0.12065 -0.305054)
			(end -0.12065 -0.2794)
			(stroke
				(width 0.1)
				(type default)
			)
			(layer "F.Fab")
		)
		(fp_line
			(start -0.67945 -0.305054)
			(end -0.12065 -0.305054)
			(stroke
				(width 0.1)
				(type default)
			)
			(layer "F.Fab")
		)
		(fp_line
			(start 0.67945 -0.3048)
			(end 0.67945 0.3048)
			(stroke
				(width 0.1)
				(type default)
			)
			(layer "F.Fab")
		)
		(fp_line
			(start 0.12065 -0.3048)
			(end 0.67945 -0.3048)
			(stroke
				(width 0.1)
				(type default)
			)
			(layer "F.Fab")
		)
		(fp_line
			(start 0.12065 -0.2794)
			(end 0.12065 -0.3048)
			(stroke
				(width 0.1)
				(type default)
			)
			(layer "F.Fab")
		)
		(fp_line
			(start -0.12065 -0.2794)
			(end 0.12065 -0.2794)
			(stroke
				(width 0.1)
				(type default)
			)
			(layer "F.Fab")
		)
		(fp_line
			(start 0.120396 0.2794)
			(end -0.12065 0.2794)
			(stroke
				(width 0.1)
				(type default)
			)
			(layer "F.Fab")
		)
		(fp_line
			(start -0.12065 0.2794)
			(end -0.12065 0.3048)
			(stroke
				(width 0.1)
				(type default)
			)
			(layer "F.Fab")
		)
		(fp_line
			(start 0.67945 0.3048)
			(end 0.120396 0.3048)
			(stroke
				(width 0.1)
				(type default)
			)
			(layer "F.Fab")
		)
		(fp_line
			(start 0.120396 0.3048)
			(end 0.120396 0.2794)
			(stroke
				(width 0.1)
				(type default)
			)
			(layer "F.Fab")
		)
		(fp_line
			(start -0.12065 0.3048)
			(end -0.67945 0.3048)
			(stroke
				(width 0.1)
				(type default)
			)
			(layer "F.Fab")
		)
		(fp_line
			(start -0.67945 0.3048)
			(end -0.67945 -0.305054)
			(stroke
				(width 0.1)
				(type default)
			)
			(layer "F.Fab")
		)
		(pad "1" smd circle
			(at -0.40005 0 90)
			(size 0 0)
			(layers "F.Cu" "F.Mask" "F.Paste")
			(net "SW_P12V_PVCCINFAON_CPU1_FLT")
		)
		(pad "2" smd circle
			(at 0.40005 0 90)
			(size 0 0)
			(layers "F.Cu" "F.Mask" "F.Paste")
			(net "GND")
		)
	)
)
